# T6G (Grand Teton) — schematic netlist excerpt (pin names and nets, part order shuffled) for the footprints in the layout excerpt that follows; sources: Cadence DE-HDL packaged netlist, KiCad conversion of 04192023_DAF0TMB3IC0_F0TG_MB_C_brd_V02_OCP.brd

PR81  Q_RES  5.6 1% CHIP  pkg 0402LF  page 201 : A = SW_PVDDCR_CPU1_P0_BOOT2 ; B = SW_PVDDCR_CPU1_P0_BOOT2_R
R283  Q_RES  0 5% CHIP  pkg 0402LF  page 81 : A = PWRGD_PVDDIO_P1 ; B = FM_PWRGD_PVDDIO_P1

(kicad_pcb
	(version 20260206)
	(generator "pcbnew")
	(generator_version "10.0")
	(general
		(thickness 1.6)
		(legacy_teardrops no)
	)
	(paper "A4")
	(title_block
		(title "04192023_DAF0TMB3IC0_F0TG_MB_C_brd_V02_OCP.brd")
		(comment 1 "Grand Teton / footprints 4336-4337 of 8354")
	)
	(layers
		(0 "F.Cu" signal "TOP")
		(4 "In1.Cu" signal "GND")
		(6 "In2.Cu" signal "IN1")
		(8 "In3.Cu" signal "GND1")
		(10 "In4.Cu" signal "IN2")
		(12 "In5.Cu" signal "GND2")
		(14 "In6.Cu" signal "IN3")
		(16 "In7.Cu" signal "GND3")
		(18 "In8.Cu" signal "VCC")
		(20 "In9.Cu" signal "VCC1")
		(22 "In10.Cu" signal "GND4")
		(24 "In11.Cu" signal "IN4")
		(26 "In12.Cu" signal "GND5")
		(28 "In13.Cu" signal "IN5")
		(30 "In14.Cu" signal "GND6")
		(32 "In15.Cu" signal "IN6")
		(34 "In16.Cu" signal "GND7")
		(2 "B.Cu" signal "BOTTOM")
		(9 "F.Adhes" user "F.Adhesive")
		(11 "B.Adhes" user "B.Adhesive")
		(13 "F.Paste" user "Package Geometry/Pastemask Top")
		(15 "B.Paste" user "Package Geometry/Pastemask Bottom")
		(5 "F.SilkS" user "Ref Des/Silkscreen Top")
		(7 "B.SilkS" user "Ref Des/Silkscreen Bottom")
		(1 "F.Mask" user "Board Geometry/Soldermask Top")
		(3 "B.Mask" user "Board Geometry/Soldermask Bottom")
		(17 "Dwgs.User" user "User.Drawings")
		(19 "Cmts.User" user "User.Comments")
		(21 "Eco1.User" user "User.Eco1")
		(23 "Eco2.User" user "User.Eco2")
		(25 "Edge.Cuts" user "Board Geometry/Outline")
		(27 "Margin" user)
		(31 "F.CrtYd" user "Package Geometry/Place Bound Top")
		(29 "B.CrtYd" user "Package Geometry/Place Bound Bottom")
		(35 "F.Fab" user "Ref Des/Assembly Top")
		(33 "B.Fab" user "Ref Des/Assembly Bottom")
	)
	(footprint ""
		(layer "F.Cu")
		(at 197.269608 -113.625376 180)
		(property "Reference" "R283"
			(at 0 0 180)
			(layer "F.SilkS")
			(hide yes)
			(effects
				(font
					(size 1.27 1.27)
				)
			)
		)
		(property "Value" ""
			(at 0 0 180)
			(layer "F.Fab")
			(effects
				(font
					(size 1.27 1.27)
				)
			)
		)
		(duplicate_pad_numbers_are_jumpers no)
		(fp_line
			(start 0.7874 0.4064)
			(end -0.7874 0.4064)
			(stroke
				(width 0.1524)
				(type default)
			)
			(layer "F.SilkS")
		)
		(fp_line
			(start 0.7874 -0.4064)
			(end 0.7874 0.4064)
			(stroke
				(width 0.1524)
				(type default)
			)
			(layer "F.SilkS")
		)
		(fp_line
			(start -0.7874 0.4064)
			(end -0.7874 -0.4064)
			(stroke
				(width 0.1524)
				(type default)
			)
			(layer "F.SilkS")
		)
		(fp_line
			(start -0.7874 -0.4064)
			(end 0.7874 -0.4064)
			(stroke
				(width 0.1524)
				(type default)
			)
			(layer "F.SilkS")
		)
		(fp_line
			(start 0.67945 0.3048)
			(end 0.120396 0.3048)
			(stroke
				(width 0.1)
				(type default)
			)
			(layer "F.Fab")
		)
		(fp_line
			(start 0.67945 -0.3048)
			(end 0.67945 0.3048)
			(stroke
				(width 0.1)
				(type default)
			)
			(layer "F.Fab")
		)
		(fp_line
			(start 0.12065 -0.2794)
			(end 0.12065 -0.3048)
			(stroke
				(width 0.1)
				(type default)
			)
			(layer "F.Fab")
		)
		(fp_line
			(start 0.12065 -0.3048)
			(end 0.67945 -0.3048)
			(stroke
				(width 0.1)
				(type default)
			)
			(layer "F.Fab")
		)
		(fp_line
			(start 0.120396 0.3048)
			(end 0.120396 0.2794)
			(stroke
				(width 0.1)
				(type default)
			)
			(layer "F.Fab")
		)
		(fp_line
			(start 0.120396 0.2794)
			(end -0.12065 0.2794)
			(stroke
				(width 0.1)
				(type default)
			)
			(layer "F.Fab")
		)
		(fp_line
			(start -0.12065 0.3048)
			(end -0.67945 0.3048)
			(stroke
				(width 0.1)
				(type default)
			)
			(layer "F.Fab")
		)
		(fp_line
			(start -0.12065 0.2794)
			(end -0.12065 0.3048)
			(stroke
				(width 0.1)
				(type default)
			)
			(layer "F.Fab")
		)
		(fp_line
			(start -0.12065 -0.2794)
			(end 0.12065 -0.2794)
			(stroke
				(width 0.1)
				(type default)
			)
			(layer "F.Fab")
		)
		(fp_line
			(start -0.12065 -0.305054)
			(end -0.12065 -0.2794)
			(stroke
				(width 0.1)
				(type default)
			)
			(layer "F.Fab")
		)
		(fp_line
			(start -0.67945 0.3048)
			(end -0.67945 -0.305054)
			(stroke
				(width 0.1)
				(type default)
			)
			(layer "F.Fab")
		)
		(fp_line
			(start -0.67945 -0.305054)
			(end -0.12065 -0.305054)
			(stroke
				(width 0.1)
				(type default)
			)
			(layer "F.Fab")
		)
		(pad "1" smd circle
			(at -0.40005 0 180)
			(size 0 0)
			(layers "F.Cu" "F.Mask" "F.Paste")
			(net "PWRGD_PVDDIO_P1")
		)
		(pad "2" smd circle
			(at 0.40005 0 180)
			(size 0 0)
			(layers "F.Cu" "F.Mask" "F.Paste")
			(net "FM_PWRGD_PVDDIO_P1")
		)
	)
	(footprint ""
		(layer "F.Cu")
		(at 327.46061 -339.63991 90)
		(property "Reference" "PR81"
			(at 0 0 90)
			(layer "F.SilkS")
			(hide yes)
			(effects
				(font
					(size 1.27 1.27)
				)
			)
		)
		(property "Value" ""
			(at 0 0 90)
			(layer "F.Fab")
			(effects
				(font
					(size 1.27 1.27)
				)
			)
		)
		(duplicate_pad_numbers_are_jumpers no)
		(fp_line
			(start 0.7874 -0.4064)
			(end 0.7874 0.4064)
			(stroke
				(width 0.1524)
				(type default)
			)
			(layer "F.SilkS")
		)
		(fp_line
			(start -0.7874 -0.4064)
			(end 0.7874 -0.4064)
			(stroke
				(width 0.1524)
				(type default)
			)
			(layer "F.SilkS")
		)
		(fp_line
			(start 0.7874 0.4064)
			(end -0.7874 0.4064)
			(stroke
				(width 0.1524)
				(type default)
			)
			(layer "F.SilkS")
		)
		(fp_line
			(start -0.7874 0.4064)
			(end -0.7874 -0.4064)
			(stroke
				(width 0.1524)
				(type default)
			)
			(layer "F.SilkS")
		)
		(fp_line
			(start -0.12065 -0.305054)
			(end -0.12065 -0.2794)
			(stroke
				(width 0.1)
				(type default)
			)
			(layer "F.Fab")
		)
		(fp_line
			(start -0.67945 -0.305054)
			(end -0.12065 -0.305054)
			(stroke
				(width 0.1)
				(type default)
			)
			(layer "F.Fab")
		)
		(fp_line
			(start 0.67945 -0.3048)
			(end 0.67945 0.3048)
			(stroke
				(width 0.1)
				(type default)
			)
			(layer "F.Fab")
		)
		(fp_line
			(start 0.12065 -0.3048)
			(end 0.67945 -0.3048)
			(stroke
				(width 0.1)
				(type default)
			)
			(layer "F.Fab")
		)
		(fp_line
			(start 0.12065 -0.2794)
			(end 0.12065 -0.3048)
			(stroke
				(width 0.1)
				(type default)
			)
			(layer "F.Fab")
		)
		(fp_line
			(start -0.12065 -0.2794)
			(end 0.12065 -0.2794)
			(stroke
				(width 0.1)
				(type default)
			)
			(layer "F.Fab")
		)
		(fp_line
			(start 0.120396 0.2794)
			(end -0.12065 0.2794)
			(stroke
				(width 0.1)
				(type default)
			)
			(layer "F.Fab")
		)
		(fp_line
			(start -0.12065 0.2794)
			(end -0.12065 0.3048)
			(stroke
				(width 0.1)
				(type default)
			)
			(layer "F.Fab")
		)
		(fp_line
			(start 0.67945 0.3048)
			(end 0.120396 0.3048)
			(stroke
				(width 0.1)
				(type default)
			)
			(layer "F.Fab")
		)
		(fp_line
			(start 0.120396 0.3048)
			(end 0.120396 0.2794)
			(stroke
				(width 0.1)
				(type default)
			)
			(layer "F.Fab")
		)
		(fp_line
			(start -0.12065 0.3048)
			(end -0.67945 0.3048)
			(stroke
				(width 0.1)
				(type default)
			)
			(layer "F.Fab")
		)
		(fp_line
			(start -0.67945 0.3048)
			(end -0.67945 -0.305054)
			(stroke
				(width 0.1)
				(type default)
			)
			(layer "F.Fab")
		)
		(pad "1" smd circle
			(at -0.40005 0 90)
			(size 0 0)
			(layers "F.Cu" "F.Mask" "F.Paste")
			(net "SW_PVDDCR_CPU1_P0_BOOT2")
		)
		(pad "2" smd circle
			(at 0.40005 0 90)
			(size 0 0)
			(layers "F.Cu" "F.Mask" "F.Paste")
			(net "SW_PVDDCR_CPU1_P0_BOOT2_R")
		)
	)
)
